(kicad_pcb
	(version 20260206)
	(generator "pcbnew")
	(generator_version "10.0")
	(general
		(thickness 1.6)
		(legacy_teardrops no)
	)
	(paper "A4")
	(title_block
		(title "fcb — Lightning_FCB_BRD.brd")
		(comment 1 "Lightning (Wiwynn / Facebook NVMe JBOF) / footprints 97-104 of 495")
	)
	(layers
		(0 "F.Cu" signal "TOP")
		(4 "In1.Cu" signal "L2GND")
		(6 "In2.Cu" signal "L3VCC")
		(2 "B.Cu" signal "BOTTOM")
		(9 "F.Adhes" user "F.Adhesive")
		(11 "B.Adhes" user "B.Adhesive")
		(13 "F.Paste" user "Package Geometry/Pastemask Top")
		(15 "B.Paste" user "Package Geometry/Pastemask Bottom")
		(5 "F.SilkS" user "Ref Des/Silkscreen Top")
		(7 "B.SilkS" user "Ref Des/Silkscreen Bottom")
		(1 "F.Mask" user "Board Geometry/Soldermask Top")
		(3 "B.Mask" user "Board Geometry/Soldermask Bottom")
		(17 "Dwgs.User" user "User.Drawings")
		(19 "Cmts.User" user "User.Comments")
		(21 "Eco1.User" user "User.Eco1")
		(23 "Eco2.User" user "User.Eco2")
		(25 "Edge.Cuts" user "Board Geometry/Outline")
		(27 "Margin" user)
		(31 "F.CrtYd" user "Package Geometry/Place Bound Top")
		(29 "B.CrtYd" user "Package Geometry/Place Bound Bottom")
		(35 "F.Fab" user "Ref Des/Assembly Top")
		(33 "B.Fab" user "Ref Des/Assembly Bottom")
	)
	(footprint ""
		(layer "F.Cu")
		(at 18.8214 -259.3086 -90)
		(property "Reference" "R78"
			(at 0 0 270)
			(layer "F.SilkS")
			(hide yes)
			(effects
				(font
					(size 1.27 1.27)
				)
			)
		)
		(property "Value" "4K7R2F-GP"
			(at 0.064008 -3.993896 270)
			(unlocked yes)
			(layer "F.Fab")
			(hide yes)
			(effects
				(font
					(size 1.016 1.016)
					(thickness 0.1524)
				)
			)
		)
		(property "Device Type" "R402H16"
			(at 0.064008 -5.517896 270)
			(unlocked yes)
			(layer "F.Fab")
			(hide yes)
			(effects
				(font
					(size 1.016 1.016)
					(thickness 0.1524)
				)
			)
		)
		(duplicate_pad_numbers_are_jumpers no)
		(fp_line
			(start -0.508 -0.9398)
			(end -0.508 0.9398)
			(stroke
				(width 0.1524)
				(type default)
			)
			(layer "F.SilkS")
		)
		(fp_line
			(start 0.508 -0.9398)
			(end -0.508 -0.9398)
			(stroke
				(width 0.1524)
				(type default)
			)
			(layer "F.SilkS")
		)
		(fp_rect
			(start -0.508 0.9398)
			(end 0.508 -0.9398)
			(stroke
				(width 0)
				(type default)
			)
			(fill no)
			(layer "F.CrtYd")
		)
		(fp_rect
			(start -0.508 0.9398)
			(end 0.508 -0.9398)
			(stroke
				(width 0)
				(type default)
			)
			(fill no)
			(layer "F.Fab")
		)
		(pad "1" smd custom
			(at 0 -0.4445 270)
			(size 0.1397 0.1397)
			(layers "F.Cu" "F.Mask" "F.Paste")
			(net "P12V")
			(options
				(clearance outline)
				(anchor circle)
			)
			(primitives
				(gr_poly
					(pts
						(arc
							(start -0.1778 -0.2794)
							(mid -0.249642 -0.249642)
							(end -0.2794 -0.1778)
						)
						(arc
							(start -0.2794 0.1778)
							(mid -0.249642 0.249642)
							(end -0.1778 0.2794)
						)
						(arc
							(start 0.1778 0.2794)
							(mid 0.249642 0.249642)
							(end 0.2794 0.1778)
						)
						(arc
							(start 0.2794 -0.1778)
							(mid 0.249642 -0.249642)
							(end 0.1778 -0.2794)
						)
					)
					(width 0)
					(fill yes)
				)
			)
		)
		(pad "2" smd custom
			(at 0 0.4445 270)
			(size 0.1397 0.1397)
			(layers "F.Cu" "F.Mask" "F.Paste")
			(net "PWM_OUT_FAN3_NET")
			(options
				(clearance outline)
				(anchor circle)
			)
			(primitives
				(gr_poly
					(pts
						(arc
							(start -0.1778 -0.2794)
							(mid -0.249642 -0.249642)
							(end -0.2794 -0.1778)
						)
						(arc
							(start -0.2794 0.1778)
							(mid -0.249642 0.249642)
							(end -0.1778 0.2794)
						)
						(arc
							(start 0.1778 0.2794)
							(mid 0.249642 0.249642)
							(end 0.2794 0.1778)
						)
						(arc
							(start 0.2794 -0.1778)
							(mid 0.249642 -0.249642)
							(end 0.1778 -0.2794)
						)
					)
					(width 0)
					(fill yes)
				)
			)
		)
	)
	(footprint ""
		(layer "F.Cu")
		(at 34.29 -254.381 180)
		(property "Reference" "R106"
			(at 0 0 180)
			(layer "F.SilkS")
			(hide yes)
			(effects
				(font
					(size 1.27 1.27)
				)
			)
		)
		(property "Value" "0R2J-2-GP"
			(at 0.064008 -3.993896 180)
			(unlocked yes)
			(layer "F.Fab")
			(hide yes)
			(effects
				(font
					(size 1.016 1.016)
					(thickness 0.1524)
				)
			)
		)
		(property "Device Type" "R402H16"
			(at 0.064008 -5.517896 180)
			(unlocked yes)
			(layer "F.Fab")
			(hide yes)
			(effects
				(font
					(size 1.016 1.016)
					(thickness 0.1524)
				)
			)
		)
		(duplicate_pad_numbers_are_jumpers no)
		(fp_line
			(start 0.508 -0.9398)
			(end -0.508 -0.9398)
			(stroke
				(width 0.1524)
				(type default)
			)
			(layer "F.SilkS")
		)
		(fp_line
			(start -0.508 -0.9398)
			(end -0.508 0.9398)
			(stroke
				(width 0.1524)
				(type default)
			)
			(layer "F.SilkS")
		)
		(fp_rect
			(start -0.508 0.9398)
			(end 0.508 -0.9398)
			(stroke
				(width 0)
				(type default)
			)
			(fill no)
			(layer "F.CrtYd")
		)
		(fp_rect
			(start -0.508 0.9398)
			(end 0.508 -0.9398)
			(stroke
				(width 0)
				(type default)
			)
			(fill no)
			(layer "F.Fab")
		)
		(pad "1" smd custom
			(at 0 -0.4445 180)
			(size 0.1397 0.1397)
			(layers "F.Cu" "F.Mask" "F.Paste")
			(net "I2C_C_SDA_LEDDRV")
			(options
				(clearance outline)
				(anchor circle)
			)
			(primitives
				(gr_poly
					(pts
						(arc
							(start -0.1778 -0.2794)
							(mid -0.249642 -0.249642)
							(end -0.2794 -0.1778)
						)
						(arc
							(start -0.2794 0.1778)
							(mid -0.249642 0.249642)
							(end -0.1778 0.2794)
						)
						(arc
							(start 0.1778 0.2794)
							(mid 0.249642 0.249642)
							(end 0.2794 0.1778)
						)
						(arc
							(start 0.2794 -0.1778)
							(mid 0.249642 -0.249642)
							(end 0.1778 -0.2794)
						)
					)
					(width 0)
					(fill yes)
				)
			)
		)
		(pad "2" smd custom
			(at 0 0.4445 180)
			(size 0.1397 0.1397)
			(layers "F.Cu" "F.Mask" "F.Paste")
			(net "I2C_C_SDA")
			(options
				(clearance outline)
				(anchor circle)
			)
			(primitives
				(gr_poly
					(pts
						(arc
							(start -0.1778 -0.2794)
							(mid -0.249642 -0.249642)
							(end -0.2794 -0.1778)
						)
						(arc
							(start -0.2794 0.1778)
							(mid -0.249642 0.249642)
							(end -0.1778 0.2794)
						)
						(arc
							(start 0.1778 0.2794)
							(mid 0.249642 0.249642)
							(end 0.2794 0.1778)
						)
						(arc
							(start 0.2794 -0.1778)
							(mid 0.249642 -0.249642)
							(end 0.1778 -0.2794)
						)
					)
					(width 0)
					(fill yes)
				)
			)
		)
	)
	(footprint ""
		(layer "F.Cu")
		(at 39.878 -240.665 180)
		(property "Reference" "R155"
			(at 0 0 180)
			(layer "F.SilkS")
			(hide yes)
			(effects
				(font
					(size 1.27 1.27)
				)
			)
		)
		(property "Value" "330R2J-3-GP"
			(at 0.064008 -3.993896 180)
			(unlocked yes)
			(layer "F.Fab")
			(hide yes)
			(effects
				(font
					(size 1.016 1.016)
					(thickness 0.1524)
				)
			)
		)
		(property "Device Type" "R402H16"
			(at 0.064008 -5.517896 180)
			(unlocked yes)
			(layer "F.Fab")
			(hide yes)
			(effects
				(font
					(size 1.016 1.016)
					(thickness 0.1524)
				)
			)
		)
		(duplicate_pad_numbers_are_jumpers no)
		(fp_line
			(start 0.508 -0.9398)
			(end -0.508 -0.9398)
			(stroke
				(width 0.1524)
				(type default)
			)
			(layer "F.SilkS")
		)
		(fp_line
			(start -0.508 -0.9398)
			(end -0.508 0.9398)
			(stroke
				(width 0.1524)
				(type default)
			)
			(layer "F.SilkS")
		)
		(fp_rect
			(start -0.508 0.9398)
			(end 0.508 -0.9398)
			(stroke
				(width 0)
				(type default)
			)
			(fill no)
			(layer "F.CrtYd")
		)
		(fp_rect
			(start -0.508 0.9398)
			(end 0.508 -0.9398)
			(stroke
				(width 0)
				(type default)
			)
			(fill no)
			(layer "F.Fab")
		)
		(pad "1" smd custom
			(at 0 -0.4445 180)
			(size 0.1397 0.1397)
			(layers "F.Cu" "F.Mask" "F.Paste")
			(net "P3V3")
			(options
				(clearance outline)
				(anchor circle)
			)
			(primitives
				(gr_poly
					(pts
						(arc
							(start -0.1778 -0.2794)
							(mid -0.249642 -0.249642)
							(end -0.2794 -0.1778)
						)
						(arc
							(start -0.2794 0.1778)
							(mid -0.249642 0.249642)
							(end -0.1778 0.2794)
						)
						(arc
							(start 0.1778 0.2794)
							(mid 0.249642 0.249642)
							(end 0.2794 0.1778)
						)
						(arc
							(start 0.2794 -0.1778)
							(mid 0.249642 -0.249642)
							(end 0.1778 -0.2794)
						)
					)
					(width 0)
					(fill yes)
				)
			)
		)
		(pad "2" smd custom
			(at 0 0.4445 180)
			(size 0.1397 0.1397)
			(layers "F.Cu" "F.Mask" "F.Paste")
			(net "LED_DR_LED3")
			(options
				(clearance outline)
				(anchor circle)
			)
			(primitives
				(gr_poly
					(pts
						(arc
							(start -0.1778 -0.2794)
							(mid -0.249642 -0.249642)
							(end -0.2794 -0.1778)
						)
						(arc
							(start -0.2794 0.1778)
							(mid -0.249642 0.249642)
							(end -0.1778 0.2794)
						)
						(arc
							(start 0.1778 0.2794)
							(mid 0.249642 0.249642)
							(end 0.2794 0.1778)
						)
						(arc
							(start 0.2794 -0.1778)
							(mid 0.249642 -0.249642)
							(end 0.1778 -0.2794)
						)
					)
					(width 0)
					(fill yes)
				)
			)
		)
	)
	(footprint ""
		(layer "F.Cu")
		(at 35.8394 -357.097584 180)
		(property "Reference" "D19"
			(at 0 0 180)
			(layer "F.SilkS")
			(hide yes)
			(effects
				(font
					(size 1.27 1.27)
				)
			)
		)
		(property "Value" "CH751H-40PT-1GP"
			(at -0.1016 -4.4958 180)
			(unlocked yes)
			(layer "F.Fab")
			(hide yes)
			(effects
				(font
					(size 1.016 1.016)
					(thickness 0.1524)
				)
			)
		)
		(property "Device Type" "SOD80CAKH36"
			(at -0.1016 -6.0198 180)
			(unlocked yes)
			(layer "F.Fab")
			(hide yes)
			(effects
				(font
					(size 1.016 1.016)
					(thickness 0.1524)
				)
			)
		)
		(duplicate_pad_numbers_are_jumpers no)
		(fp_line
			(start 0.8128 1.8796)
			(end 0.8128 -1.8796)
			(stroke
				(width 0.1524)
				(type default)
			)
			(layer "F.SilkS")
		)
		(fp_line
			(start 0.8128 -1.8796)
			(end -0.8128 -1.8796)
			(stroke
				(width 0.1524)
				(type default)
			)
			(layer "F.SilkS")
		)
		(fp_line
			(start -0.6858 2.0066)
			(end 0.6858 2.0066)
			(stroke
				(width 0.4064)
				(type default)
			)
			(layer "F.SilkS")
		)
		(fp_line
			(start -0.8128 1.8796)
			(end 0.8128 1.8796)
			(stroke
				(width 0.1524)
				(type default)
			)
			(layer "F.SilkS")
		)
		(fp_line
			(start -0.8128 -1.8796)
			(end -0.8128 1.8796)
			(stroke
				(width 0.1524)
				(type default)
			)
			(layer "F.SilkS")
		)
		(fp_rect
			(start -0.889 2.2098)
			(end 0.889 -1.9558)
			(stroke
				(width 0)
				(type default)
			)
			(fill no)
			(layer "F.CrtYd")
		)
		(fp_rect
			(start -0.889 2.2098)
			(end 0.889 -1.9558)
			(stroke
				(width 0)
				(type default)
			)
			(fill no)
			(layer "F.Fab")
		)
		(pad "A" smd rect
			(at 0 -1.0668 180)
			(size 0.762 1.1684)
			(layers "F.Cu" "F.Mask" "F.Paste")
			(net "OTP_RETRY_C")
		)
		(pad "K" smd rect
			(at 0 1.0668 180)
			(size 0.762 1.1684)
			(layers "F.Cu" "F.Mask" "F.Paste")
			(net "OTP_RETRY_DIODE")
		)
	)
	(footprint ""
		(layer "F.Cu")
		(at 31.012638 -289.229292 -90)
		(property "Reference" "F5"
			(at 0 0 270)
			(layer "F.SilkS")
			(hide yes)
			(effects
				(font
					(size 1.27 1.27)
				)
			)
		)
		(property "Value" "FUSE-3A15V-GP"
			(at 0.2286 -10.5918 270)
			(unlocked yes)
			(layer "F.Fab")
			(hide yes)
			(effects
				(font
					(size 1.016 1.016)
					(thickness 0.1524)
				)
			)
		)
		(property "Device Type" "FUSE-7452-UH50"
			(at 0.2286 -12.4968 270)
			(unlocked yes)
			(layer "F.Fab")
			(hide yes)
			(effects
				(font
					(size 1.016 1.016)
					(thickness 0.1524)
				)
			)
		)
		(duplicate_pad_numbers_are_jumpers no)
		(fp_line
			(start -4.9276 2.921)
			(end -4.9276 -2.921)
			(stroke
				(width 0.1524)
				(type default)
			)
			(layer "F.SilkS")
		)
		(fp_line
			(start 4.9276 2.921)
			(end -4.9276 2.921)
			(stroke
				(width 0.1524)
				(type default)
			)
			(layer "F.SilkS")
		)
		(fp_line
			(start -4.9276 -2.921)
			(end 4.9276 -2.921)
			(stroke
				(width 0.1524)
				(type default)
			)
			(layer "F.SilkS")
		)
		(fp_line
			(start 4.9276 -2.921)
			(end 4.9276 2.921)
			(stroke
				(width 0.1524)
				(type default)
			)
			(layer "F.SilkS")
		)
		(fp_poly
			(pts
				(xy -5.08 3.0988) (xy 5.08 3.0988) (xy 5.08 -3.0988) (xy -5.08 -3.0988)
			)
			(stroke
				(width 0)
				(type default)
			)
			(fill no)
			(layer "F.CrtYd")
		)
		(fp_poly
			(pts
				(xy -5.08 -3.0988) (xy 5.08 -3.0988) (xy 5.08 3.0988) (xy -5.08 3.0988)
			)
			(stroke
				(width 0)
				(type default)
			)
			(fill no)
			(layer "F.Fab")
		)
		(pad "1" smd rect
			(at -3.4036 0 270)
			(size 2.2098 5.2832)
			(layers "F.Cu" "F.Mask" "F.Paste")
			(net "P12V_FAN2")
		)
		(pad "2" smd rect
			(at 3.4036 0 270)
			(size 2.2098 5.2832)
			(layers "F.Cu" "F.Mask" "F.Paste")
			(net "P12V")
		)
	)
	(footprint ""
		(layer "F.Cu")
		(at 19.558 -185.1914 180)
		(property "Reference" "R89"
			(at 0 0 180)
			(layer "F.SilkS")
			(hide yes)
			(effects
				(font
					(size 1.27 1.27)
				)
			)
		)
		(property "Value" "10KR2F-2-GP"
			(at 0.064008 -3.993896 180)
			(unlocked yes)
			(layer "F.Fab")
			(hide yes)
			(effects
				(font
					(size 1.016 1.016)
					(thickness 0.1524)
				)
			)
		)
		(property "Device Type" "R402H16"
			(at 0.064008 -5.517896 180)
			(unlocked yes)
			(layer "F.Fab")
			(hide yes)
			(effects
				(font
					(size 1.016 1.016)
					(thickness 0.1524)
				)
			)
		)
		(duplicate_pad_numbers_are_jumpers no)
		(fp_line
			(start 0.508 -0.9398)
			(end -0.508 -0.9398)
			(stroke
				(width 0.1524)
				(type default)
			)
			(layer "F.SilkS")
		)
		(fp_line
			(start -0.508 -0.9398)
			(end -0.508 0.9398)
			(stroke
				(width 0.1524)
				(type default)
			)
			(layer "F.SilkS")
		)
		(fp_rect
			(start -0.508 0.9398)
			(end 0.508 -0.9398)
			(stroke
				(width 0)
				(type default)
			)
			(fill no)
			(layer "F.CrtYd")
		)
		(fp_rect
			(start -0.508 0.9398)
			(end 0.508 -0.9398)
			(stroke
				(width 0)
				(type default)
			)
			(fill no)
			(layer "F.Fab")
		)
		(pad "1" smd custom
			(at 0 -0.4445 180)
			(size 0.1397 0.1397)
			(layers "F.Cu" "F.Mask" "F.Paste")
			(net "FANIN_8")
			(options
				(clearance outline)
				(anchor circle)
			)
			(primitives
				(gr_poly
					(pts
						(arc
							(start -0.1778 -0.2794)
							(mid -0.249642 -0.249642)
							(end -0.2794 -0.1778)
						)
						(arc
							(start -0.2794 0.1778)
							(mid -0.249642 0.249642)
							(end -0.1778 0.2794)
						)
						(arc
							(start 0.1778 0.2794)
							(mid 0.249642 0.249642)
							(end 0.2794 0.1778)
						)
						(arc
							(start 0.2794 -0.1778)
							(mid 0.249642 -0.249642)
							(end 0.1778 -0.2794)
						)
					)
					(width 0)
					(fill yes)
				)
			)
		)
		(pad "2" smd custom
			(at 0 0.4445 180)
			(size 0.1397 0.1397)
			(layers "F.Cu" "F.Mask" "F.Paste")
			(net "GND")
			(options
				(clearance outline)
				(anchor circle)
			)
			(primitives
				(gr_poly
					(pts
						(arc
							(start -0.1778 -0.2794)
							(mid -0.249642 -0.249642)
							(end -0.2794 -0.1778)
						)
						(arc
							(start -0.2794 0.1778)
							(mid -0.249642 0.249642)
							(end -0.1778 0.2794)
						)
						(arc
							(start 0.1778 0.2794)
							(mid 0.249642 0.249642)
							(end 0.2794 0.1778)
						)
						(arc
							(start 0.2794 -0.1778)
							(mid 0.249642 -0.249642)
							(end 0.1778 -0.2794)
						)
					)
					(width 0)
					(fill yes)
				)
			)
		)
	)
	(footprint ""
		(layer "F.Cu")
		(at 8.3566 -422.275)
		(property "Reference" "R119"
			(at 0 0 0)
			(layer "F.SilkS")
			(hide yes)
			(effects
				(font
					(size 1.27 1.27)
				)
			)
		)
		(property "Value" "2KR2F-3-GP"
			(at 0.064008 -3.993896 0)
			(unlocked yes)
			(layer "F.Fab")
			(hide yes)
			(effects
				(font
					(size 1.016 1.016)
					(thickness 0.1524)
				)
			)
		)
		(property "Device Type" "R402H16"
			(at 0.064008 -5.517896 0)
			(unlocked yes)
			(layer "F.Fab")
			(hide yes)
			(effects
				(font
					(size 1.016 1.016)
					(thickness 0.1524)
				)
			)
		)
		(duplicate_pad_numbers_are_jumpers no)
		(fp_line
			(start -0.508 -0.9398)
			(end -0.508 0.9398)
			(stroke
				(width 0.1524)
				(type default)
			)
			(layer "F.SilkS")
		)
		(fp_line
			(start 0.508 -0.9398)
			(end -0.508 -0.9398)
			(stroke
				(width 0.1524)
				(type default)
			)
			(layer "F.SilkS")
		)
		(fp_rect
			(start -0.508 0.9398)
			(end 0.508 -0.9398)
			(stroke
				(width 0)
				(type default)
			)
			(fill no)
			(layer "F.CrtYd")
		)
		(fp_rect
			(start -0.508 0.9398)
			(end 0.508 -0.9398)
			(stroke
				(width 0)
				(type default)
			)
			(fill no)
			(layer "F.Fab")
		)
		(pad "1" smd custom
			(at 0 -0.4445)
			(size 0.1397 0.1397)
			(layers "F.Cu" "F.Mask" "F.Paste")
			(net "LED_DR_LED1")
			(options
				(clearance outline)
				(anchor circle)
			)
			(primitives
				(gr_poly
					(pts
						(arc
							(start -0.1778 -0.2794)
							(mid -0.249642 -0.249642)
							(end -0.2794 -0.1778)
						)
						(arc
							(start -0.2794 0.1778)
							(mid -0.249642 0.249642)
							(end -0.1778 0.2794)
						)
						(arc
							(start 0.1778 0.2794)
							(mid 0.249642 0.249642)
							(end 0.2794 0.1778)
						)
						(arc
							(start 0.2794 -0.1778)
							(mid 0.249642 -0.249642)
							(end 0.1778 -0.2794)
						)
					)
					(width 0)
					(fill yes)
				)
			)
		)
		(pad "2" smd custom
			(at 0 0.4445)
			(size 0.1397 0.1397)
			(layers "F.Cu" "F.Mask" "F.Paste")
			(net "LED_DR_LED1_B")
			(options
				(clearance outline)
				(anchor circle)
			)
			(primitives
				(gr_poly
					(pts
						(arc
							(start -0.1778 -0.2794)
							(mid -0.249642 -0.249642)
							(end -0.2794 -0.1778)
						)
						(arc
							(start -0.2794 0.1778)
							(mid -0.249642 0.249642)
							(end -0.1778 0.2794)
						)
						(arc
							(start 0.1778 0.2794)
							(mid 0.249642 0.249642)
							(end 0.2794 0.1778)
						)
						(arc
							(start 0.2794 -0.1778)
							(mid 0.249642 -0.249642)
							(end 0.1778 -0.2794)
						)
					)
					(width 0)
					(fill yes)
				)
			)
		)
	)
	(footprint ""
		(layer "F.Cu")
		(at 20.7518 -173.2788 -90)
		(property "Reference" "R183"
			(at 0 0 270)
			(layer "F.SilkS")
			(hide yes)
			(effects
				(font
					(size 1.27 1.27)
				)
			)
		)
		(property "Value" "0R2J-2-GP"
			(at 0.064008 -3.993896 270)
			(unlocked yes)
			(layer "F.Fab")
			(hide yes)
			(effects
				(font
					(size 1.016 1.016)
					(thickness 0.1524)
				)
			)
		)
		(property "Device Type" "R402H16"
			(at 0.064008 -5.517896 270)
			(unlocked yes)
			(layer "F.Fab")
			(hide yes)
			(effects
				(font
					(size 1.016 1.016)
					(thickness 0.1524)
				)
			)
		)
		(duplicate_pad_numbers_are_jumpers no)
		(fp_line
			(start -0.508 -0.9398)
			(end -0.508 0.9398)
			(stroke
				(width 0.1524)
				(type default)
			)
			(layer "F.SilkS")
		)
		(fp_line
			(start 0.508 -0.9398)
			(end -0.508 -0.9398)
			(stroke
				(width 0.1524)
				(type default)
			)
			(layer "F.SilkS")
		)
		(fp_rect
			(start -0.508 0.9398)
			(end 0.508 -0.9398)
			(stroke
				(width 0)
				(type default)
			)
			(fill no)
			(layer "F.CrtYd")
		)
		(fp_rect
			(start -0.508 0.9398)
			(end 0.508 -0.9398)
			(stroke
				(width 0)
				(type default)
			)
			(fill no)
			(layer "F.Fab")
		)
		(pad "1" smd custom
			(at 0 -0.4445 270)
			(size 0.1397 0.1397)
			(layers "F.Cu" "F.Mask" "F.Paste")
			(net "THERMHOT#")
			(options
				(clearance outline)
				(anchor circle)
			)
			(primitives
				(gr_poly
					(pts
						(arc
							(start -0.1778 -0.2794)
							(mid -0.249642 -0.249642)
							(end -0.2794 -0.1778)
						)
						(arc
							(start -0.2794 0.1778)
							(mid -0.249642 0.249642)
							(end -0.1778 0.2794)
						)
						(arc
							(start 0.1778 0.2794)
							(mid 0.249642 0.249642)
							(end 0.2794 0.1778)
						)
						(arc
							(start 0.2794 -0.1778)
							(mid 0.249642 -0.249642)
							(end 0.1778 -0.2794)
						)
					)
					(width 0)
					(fill yes)
				)
			)
		)
		(pad "2" smd custom
			(at 0 0.4445 270)
			(size 0.1397 0.1397)
			(layers "F.Cu" "F.Mask" "F.Paste")
			(net "THERMHOT#_R")
			(options
				(clearance outline)
				(anchor circle)
			)
			(primitives
				(gr_poly
					(pts
						(arc
							(start -0.1778 -0.2794)
							(mid -0.249642 -0.249642)
							(end -0.2794 -0.1778)
						)
						(arc
							(start -0.2794 0.1778)
							(mid -0.249642 0.249642)
							(end -0.1778 0.2794)
						)
						(arc
							(start 0.1778 0.2794)
							(mid 0.249642 0.249642)
							(end 0.2794 0.1778)
						)
						(arc
							(start 0.2794 -0.1778)
							(mid 0.249642 -0.249642)
							(end 0.1778 -0.2794)
						)
					)
					(width 0)
					(fill yes)
				)
			)
		)
	)
)
